(kicad_pcb
	(version 20260206)
	(generator "pcbnew")
	(generator_version "10.0")
	(general
		(thickness 1.6)
		(legacy_teardrops no)
	)
	(paper "A4")
	(title_block
		(title "01162023_DA0F0TEBIF0_F0T_Expander_BD_F_brd_V02_OCP.brd")
		(comment 1 "Grand Teton / footprints 3646-3652 of 9728")
	)
	(layers
		(0 "F.Cu" signal "TOP")
		(4 "In1.Cu" signal "GND")
		(6 "In2.Cu" signal "VCC")
		(8 "In3.Cu" signal "VCC1")
		(10 "In4.Cu" signal "GND1")
		(12 "In5.Cu" signal "IN1")
		(14 "In6.Cu" signal "GND2")
		(16 "In7.Cu" signal "IN2")
		(18 "In8.Cu" signal "GND3")
		(20 "In9.Cu" signal "IN3")
		(22 "In10.Cu" signal "GND4")
		(24 "In11.Cu" signal "IN4")
		(26 "In12.Cu" signal "GND5")
		(28 "In13.Cu" signal "IN5")
		(30 "In14.Cu" signal "GND6")
		(32 "In15.Cu" signal "IN6")
		(34 "In16.Cu" signal "GND7")
		(2 "B.Cu" signal "BOTTOM")
		(9 "F.Adhes" user "F.Adhesive")
		(11 "B.Adhes" user "B.Adhesive")
		(13 "F.Paste" user "Package Geometry/Pastemask Top")
		(15 "B.Paste" user "Package Geometry/Pastemask Bottom")
		(5 "F.SilkS" user "Ref Des/Silkscreen Top")
		(7 "B.SilkS" user "Ref Des/Silkscreen Bottom")
		(1 "F.Mask" user "Board Geometry/Soldermask Top")
		(3 "B.Mask" user "Board Geometry/Soldermask Bottom")
		(17 "Dwgs.User" user "User.Drawings")
		(19 "Cmts.User" user "User.Comments")
		(21 "Eco1.User" user "User.Eco1")
		(23 "Eco2.User" user "User.Eco2")
		(25 "Edge.Cuts" user "Board Geometry/Outline")
		(27 "Margin" user)
		(31 "F.CrtYd" user "Package Geometry/Place Bound Top")
		(29 "B.CrtYd" user "Package Geometry/Place Bound Bottom")
		(35 "F.Fab" user "Ref Des/Assembly Top")
		(33 "B.Fab" user "Ref Des/Assembly Bottom")
	)
	(footprint ""
		(layer "F.Cu")
		(at 279.121616 -405.074374 90)
		(property "Reference" "R1812"
			(at 0 0 90)
			(layer "F.SilkS")
			(hide yes)
			(effects
				(font
					(size 1.27 1.27)
				)
			)
		)
		(property "Value" ""
			(at 0 0 90)
			(layer "F.Fab")
			(effects
				(font
					(size 1.27 1.27)
				)
			)
		)
		(duplicate_pad_numbers_are_jumpers no)
		(fp_line
			(start 0.7874 -0.4064)
			(end 0.7874 0.4064)
			(stroke
				(width 0.1524)
				(type default)
			)
			(layer "F.SilkS")
		)
		(fp_line
			(start -0.7874 -0.4064)
			(end 0.7874 -0.4064)
			(stroke
				(width 0.1524)
				(type default)
			)
			(layer "F.SilkS")
		)
		(fp_line
			(start 0.7874 0.4064)
			(end -0.7874 0.4064)
			(stroke
				(width 0.1524)
				(type default)
			)
			(layer "F.SilkS")
		)
		(fp_line
			(start -0.7874 0.4064)
			(end -0.7874 -0.4064)
			(stroke
				(width 0.1524)
				(type default)
			)
			(layer "F.SilkS")
		)
		(fp_line
			(start -0.12065 -0.305054)
			(end -0.12065 -0.2794)
			(stroke
				(width 0.1)
				(type default)
			)
			(layer "F.Fab")
		)
		(fp_line
			(start -0.67945 -0.305054)
			(end -0.12065 -0.305054)
			(stroke
				(width 0.1)
				(type default)
			)
			(layer "F.Fab")
		)
		(fp_line
			(start 0.67945 -0.3048)
			(end 0.67945 0.3048)
			(stroke
				(width 0.1)
				(type default)
			)
			(layer "F.Fab")
		)
		(fp_line
			(start 0.12065 -0.3048)
			(end 0.67945 -0.3048)
			(stroke
				(width 0.1)
				(type default)
			)
			(layer "F.Fab")
		)
		(fp_line
			(start 0.12065 -0.2794)
			(end 0.12065 -0.3048)
			(stroke
				(width 0.1)
				(type default)
			)
			(layer "F.Fab")
		)
		(fp_line
			(start -0.12065 -0.2794)
			(end 0.12065 -0.2794)
			(stroke
				(width 0.1)
				(type default)
			)
			(layer "F.Fab")
		)
		(fp_line
			(start 0.120396 0.2794)
			(end -0.12065 0.2794)
			(stroke
				(width 0.1)
				(type default)
			)
			(layer "F.Fab")
		)
		(fp_line
			(start -0.12065 0.2794)
			(end -0.12065 0.3048)
			(stroke
				(width 0.1)
				(type default)
			)
			(layer "F.Fab")
		)
		(fp_line
			(start 0.67945 0.3048)
			(end 0.120396 0.3048)
			(stroke
				(width 0.1)
				(type default)
			)
			(layer "F.Fab")
		)
		(fp_line
			(start 0.120396 0.3048)
			(end 0.120396 0.2794)
			(stroke
				(width 0.1)
				(type default)
			)
			(layer "F.Fab")
		)
		(fp_line
			(start -0.12065 0.3048)
			(end -0.67945 0.3048)
			(stroke
				(width 0.1)
				(type default)
			)
			(layer "F.Fab")
		)
		(fp_line
			(start -0.67945 0.3048)
			(end -0.67945 -0.305054)
			(stroke
				(width 0.1)
				(type default)
			)
			(layer "F.Fab")
		)
		(pad "1" smd circle
			(at -0.40005 0 90)
			(size 0 0)
			(layers "F.Cu" "F.Mask" "F.Paste")
			(net "P3V3_AUX")
		)
		(pad "2" smd circle
			(at 0.40005 0 90)
			(size 0 0)
			(layers "F.Cu" "F.Mask" "F.Paste")
			(net "MB_BIC_MON_BUF")
		)
	)
	(footprint ""
		(layer "F.Cu")
		(at 76.48194 -38.041072 180)
		(property "Reference" "R5885"
			(at 0 0 180)
			(layer "F.SilkS")
			(hide yes)
			(effects
				(font
					(size 1.27 1.27)
				)
			)
		)
		(property "Value" ""
			(at 0 0 180)
			(layer "F.Fab")
			(effects
				(font
					(size 1.27 1.27)
				)
			)
		)
		(duplicate_pad_numbers_are_jumpers no)
		(fp_line
			(start 0.7874 0.4064)
			(end -0.7874 0.4064)
			(stroke
				(width 0.1524)
				(type default)
			)
			(layer "F.SilkS")
		)
		(fp_line
			(start 0.7874 -0.4064)
			(end 0.7874 0.4064)
			(stroke
				(width 0.1524)
				(type default)
			)
			(layer "F.SilkS")
		)
		(fp_line
			(start -0.7874 0.4064)
			(end -0.7874 -0.4064)
			(stroke
				(width 0.1524)
				(type default)
			)
			(layer "F.SilkS")
		)
		(fp_line
			(start -0.7874 -0.4064)
			(end 0.7874 -0.4064)
			(stroke
				(width 0.1524)
				(type default)
			)
			(layer "F.SilkS")
		)
		(fp_line
			(start 0.67945 0.3048)
			(end 0.120396 0.3048)
			(stroke
				(width 0.1)
				(type default)
			)
			(layer "F.Fab")
		)
		(fp_line
			(start 0.67945 -0.3048)
			(end 0.67945 0.3048)
			(stroke
				(width 0.1)
				(type default)
			)
			(layer "F.Fab")
		)
		(fp_line
			(start 0.12065 -0.2794)
			(end 0.12065 -0.3048)
			(stroke
				(width 0.1)
				(type default)
			)
			(layer "F.Fab")
		)
		(fp_line
			(start 0.12065 -0.3048)
			(end 0.67945 -0.3048)
			(stroke
				(width 0.1)
				(type default)
			)
			(layer "F.Fab")
		)
		(fp_line
			(start 0.120396 0.3048)
			(end 0.120396 0.2794)
			(stroke
				(width 0.1)
				(type default)
			)
			(layer "F.Fab")
		)
		(fp_line
			(start 0.120396 0.2794)
			(end -0.12065 0.2794)
			(stroke
				(width 0.1)
				(type default)
			)
			(layer "F.Fab")
		)
		(fp_line
			(start -0.12065 0.3048)
			(end -0.67945 0.3048)
			(stroke
				(width 0.1)
				(type default)
			)
			(layer "F.Fab")
		)
		(fp_line
			(start -0.12065 0.2794)
			(end -0.12065 0.3048)
			(stroke
				(width 0.1)
				(type default)
			)
			(layer "F.Fab")
		)
		(fp_line
			(start -0.12065 -0.2794)
			(end 0.12065 -0.2794)
			(stroke
				(width 0.1)
				(type default)
			)
			(layer "F.Fab")
		)
		(fp_line
			(start -0.12065 -0.305054)
			(end -0.12065 -0.2794)
			(stroke
				(width 0.1)
				(type default)
			)
			(layer "F.Fab")
		)
		(fp_line
			(start -0.67945 0.3048)
			(end -0.67945 -0.305054)
			(stroke
				(width 0.1)
				(type default)
			)
			(layer "F.Fab")
		)
		(fp_line
			(start -0.67945 -0.305054)
			(end -0.12065 -0.305054)
			(stroke
				(width 0.1)
				(type default)
			)
			(layer "F.Fab")
		)
		(pad "1" smd circle
			(at -0.40005 0 180)
			(size 0 0)
			(layers "F.Cu" "F.Mask" "F.Paste")
			(net "P5V_AUX")
		)
		(pad "2" smd circle
			(at 0.40005 0 180)
			(size 0 0)
			(layers "F.Cu" "F.Mask" "F.Paste")
			(net "P3V3_SSD3_PG_G2")
		)
	)
	(footprint ""
		(layer "F.Cu")
		(at 26.439368 -350.098614 90)
		(property "Reference" "C186"
			(at 0 0 90)
			(layer "F.SilkS")
			(hide yes)
			(effects
				(font
					(size 1.27 1.27)
				)
			)
		)
		(property "Value" ""
			(at 0 0 90)
			(layer "F.Fab")
			(effects
				(font
					(size 1.27 1.27)
				)
			)
		)
		(duplicate_pad_numbers_are_jumpers no)
		(fp_line
			(start 0.299974 -0.150114)
			(end 0.299974 0.150114)
			(stroke
				(width 0.1)
				(type default)
			)
			(layer "F.Fab")
		)
		(fp_line
			(start -0.299974 -0.150114)
			(end 0.299974 -0.150114)
			(stroke
				(width 0.1)
				(type default)
			)
			(layer "F.Fab")
		)
		(fp_line
			(start 0.299974 0.150114)
			(end -0.299974 0.150114)
			(stroke
				(width 0.1)
				(type default)
			)
			(layer "F.Fab")
		)
		(fp_line
			(start -0.299974 0.150114)
			(end -0.299974 -0.150114)
			(stroke
				(width 0.1)
				(type default)
			)
			(layer "F.Fab")
		)
		(pad "1" smd rect
			(at -0.2667 0 90)
			(size 0.3048 0.381)
			(layers "F.Cu" "F.Mask" "F.Paste")
			(net "P5E_PEX0_STN7_TX_DN<115>")
		)
		(pad "2" smd rect
			(at 0.2667 0 90)
			(size 0.3048 0.381)
			(layers "F.Cu" "F.Mask" "F.Paste")
			(net "P5E_PEX0_STN7_TX_C_DN<115>")
		)
	)
	(footprint ""
		(layer "F.Cu")
		(at 299.342556 -70.844918 -90)
		(property "Reference" "PD46"
			(at 4.144518 2.161286 90)
			(unlocked yes)
			(layer "F.SilkS")
			(effects
				(font
					(size 0.7874 0.5842)
					(thickness 0.1524)
				)
				(justify left)
			)
		)
		(property "Value" ""
			(at 0 0 270)
			(layer "F.Fab")
			(effects
				(font
					(size 1.27 1.27)
				)
			)
		)
		(duplicate_pad_numbers_are_jumpers no)
		(fp_line
			(start -3.400044 1.459992)
			(end -3.400044 -1.459992)
			(stroke
				(width 0.1524)
				(type default)
			)
			(layer "F.SilkS")
		)
		(fp_line
			(start 4.107942 1.459992)
			(end -3.400044 1.459992)
			(stroke
				(width 0.1524)
				(type default)
			)
			(layer "F.SilkS")
		)
		(fp_line
			(start -3.400044 -1.459992)
			(end 4.107942 -1.459992)
			(stroke
				(width 0.1524)
				(type default)
			)
			(layer "F.SilkS")
		)
		(fp_line
			(start 4.107942 -1.459992)
			(end 4.107942 1.459992)
			(stroke
				(width 0.1524)
				(type default)
			)
			(layer "F.SilkS")
		)
		(fp_poly
			(pts
				(xy 4.107942 -1.459992) (xy 4.107942 1.459992) (xy 3.308096 1.459992) (xy 3.308096 -1.459992)
			)
			(stroke
				(width 0)
				(type default)
			)
			(fill yes)
			(layer "F.SilkS")
		)
		(fp_line
			(start -2.29997 1.459992)
			(end -2.29997 -1.459992)
			(stroke
				(width 0.1)
				(type default)
			)
			(layer "F.Fab")
		)
		(fp_line
			(start 2.29997 1.459992)
			(end -2.29997 1.459992)
			(stroke
				(width 0.1)
				(type default)
			)
			(layer "F.Fab")
		)
		(fp_line
			(start -2.29997 -1.459992)
			(end 2.29997 -1.459992)
			(stroke
				(width 0.1)
				(type default)
			)
			(layer "F.Fab")
		)
		(fp_line
			(start 2.29997 -1.459992)
			(end 2.29997 1.459992)
			(stroke
				(width 0.1)
				(type default)
			)
			(layer "F.Fab")
		)
		(fp_text user "-"
			(at 5.4102 0.29845 90)
			(unlocked yes)
			(layer "F.SilkS")
			(effects
				(font
					(size 1.905 1.4224)
					(thickness 0.1524)
				)
				(justify left)
			)
		)
		(fp_text user "+"
			(at -5.166868 -0.175006 270)
			(unlocked yes)
			(layer "F.SilkS")
			(effects
				(font
					(size 1.905 1.4224)
					(thickness 0.1524)
				)
				(justify left)
			)
		)
		(fp_text user "-"
			(at 5.4102 0.29845 90)
			(unlocked yes)
			(layer "F.Fab")
			(effects
				(font
					(size 1.905 1.4224)
					(thickness 0.1524)
				)
				(justify left)
			)
		)
		(fp_text user "+"
			(at -4.7752 -0.12065 270)
			(unlocked yes)
			(layer "F.Fab")
			(effects
				(font
					(size 1.905 1.4224)
					(thickness 0.1524)
				)
				(justify left)
			)
		)
		(pad "A" smd rect
			(at -1.999996 0)
			(size 1.7018 2.5146)
			(layers "F.Cu" "F.Mask" "F.Paste")
			(net "GND")
		)
		(pad "C" smd rect
			(at 1.999996 0)
			(size 1.7018 2.5146)
			(layers "F.Cu" "F.Mask" "F.Paste")
			(net "P12V_SSD10_R")
		)
	)
	(footprint ""
		(layer "F.Cu")
		(at 150.540974 -382.471676 180)
		(property "Reference" "R6773"
			(at 0 0 180)
			(layer "F.SilkS")
			(hide yes)
			(effects
				(font
					(size 1.27 1.27)
				)
			)
		)
		(property "Value" ""
			(at 0 0 180)
			(layer "F.Fab")
			(effects
				(font
					(size 1.27 1.27)
				)
			)
		)
		(duplicate_pad_numbers_are_jumpers no)
		(fp_line
			(start 0.7874 0.4064)
			(end -0.7874 0.4064)
			(stroke
				(width 0.1524)
				(type default)
			)
			(layer "F.SilkS")
		)
		(fp_line
			(start 0.7874 -0.4064)
			(end 0.7874 0.4064)
			(stroke
				(width 0.1524)
				(type default)
			)
			(layer "F.SilkS")
		)
		(fp_line
			(start -0.7874 0.4064)
			(end -0.7874 -0.4064)
			(stroke
				(width 0.1524)
				(type default)
			)
			(layer "F.SilkS")
		)
		(fp_line
			(start -0.7874 -0.4064)
			(end 0.7874 -0.4064)
			(stroke
				(width 0.1524)
				(type default)
			)
			(layer "F.SilkS")
		)
		(fp_line
			(start 0.67945 0.3048)
			(end 0.120396 0.3048)
			(stroke
				(width 0.1)
				(type default)
			)
			(layer "F.Fab")
		)
		(fp_line
			(start 0.67945 -0.3048)
			(end 0.67945 0.3048)
			(stroke
				(width 0.1)
				(type default)
			)
			(layer "F.Fab")
		)
		(fp_line
			(start 0.12065 -0.2794)
			(end 0.12065 -0.3048)
			(stroke
				(width 0.1)
				(type default)
			)
			(layer "F.Fab")
		)
		(fp_line
			(start 0.12065 -0.3048)
			(end 0.67945 -0.3048)
			(stroke
				(width 0.1)
				(type default)
			)
			(layer "F.Fab")
		)
		(fp_line
			(start 0.120396 0.3048)
			(end 0.120396 0.2794)
			(stroke
				(width 0.1)
				(type default)
			)
			(layer "F.Fab")
		)
		(fp_line
			(start 0.120396 0.2794)
			(end -0.12065 0.2794)
			(stroke
				(width 0.1)
				(type default)
			)
			(layer "F.Fab")
		)
		(fp_line
			(start -0.12065 0.3048)
			(end -0.67945 0.3048)
			(stroke
				(width 0.1)
				(type default)
			)
			(layer "F.Fab")
		)
		(fp_line
			(start -0.12065 0.2794)
			(end -0.12065 0.3048)
			(stroke
				(width 0.1)
				(type default)
			)
			(layer "F.Fab")
		)
		(fp_line
			(start -0.12065 -0.2794)
			(end 0.12065 -0.2794)
			(stroke
				(width 0.1)
				(type default)
			)
			(layer "F.Fab")
		)
		(fp_line
			(start -0.12065 -0.305054)
			(end -0.12065 -0.2794)
			(stroke
				(width 0.1)
				(type default)
			)
			(layer "F.Fab")
		)
		(fp_line
			(start -0.67945 0.3048)
			(end -0.67945 -0.305054)
			(stroke
				(width 0.1)
				(type default)
			)
			(layer "F.Fab")
		)
		(fp_line
			(start -0.67945 -0.305054)
			(end -0.12065 -0.305054)
			(stroke
				(width 0.1)
				(type default)
			)
			(layer "F.Fab")
		)
		(pad "1" smd circle
			(at -0.40005 0 180)
			(size 0 0)
			(layers "F.Cu" "F.Mask" "F.Paste")
			(net "PRSNT_GPU_A3_R_N")
		)
		(pad "2" smd circle
			(at 0.40005 0 180)
			(size 0 0)
			(layers "F.Cu" "F.Mask" "F.Paste")
			(net "PRSNT_GPU_A3_N")
		)
	)
	(footprint ""
		(layer "F.Cu")
		(at 241.561112 -198.746618)
		(property "Reference" "R6149"
			(at 0 0 0)
			(layer "F.SilkS")
			(hide yes)
			(effects
				(font
					(size 1.27 1.27)
				)
			)
		)
		(property "Value" ""
			(at 0 0 0)
			(layer "F.Fab")
			(effects
				(font
					(size 1.27 1.27)
				)
			)
		)
		(duplicate_pad_numbers_are_jumpers no)
		(fp_line
			(start -0.7874 -0.4064)
			(end 0.7874 -0.4064)
			(stroke
				(width 0.1524)
				(type default)
			)
			(layer "F.SilkS")
		)
		(fp_line
			(start -0.7874 0.4064)
			(end -0.7874 -0.4064)
			(stroke
				(width 0.1524)
				(type default)
			)
			(layer "F.SilkS")
		)
		(fp_line
			(start 0.7874 -0.4064)
			(end 0.7874 0.4064)
			(stroke
				(width 0.1524)
				(type default)
			)
			(layer "F.SilkS")
		)
		(fp_line
			(start 0.7874 0.4064)
			(end -0.7874 0.4064)
			(stroke
				(width 0.1524)
				(type default)
			)
			(layer "F.SilkS")
		)
		(fp_line
			(start -0.67945 -0.305054)
			(end -0.12065 -0.305054)
			(stroke
				(width 0.1)
				(type default)
			)
			(layer "F.Fab")
		)
		(fp_line
			(start -0.67945 0.3048)
			(end -0.67945 -0.305054)
			(stroke
				(width 0.1)
				(type default)
			)
			(layer "F.Fab")
		)
		(fp_line
			(start -0.12065 -0.305054)
			(end -0.12065 -0.2794)
			(stroke
				(width 0.1)
				(type default)
			)
			(layer "F.Fab")
		)
		(fp_line
			(start -0.12065 -0.2794)
			(end 0.12065 -0.2794)
			(stroke
				(width 0.1)
				(type default)
			)
			(layer "F.Fab")
		)
		(fp_line
			(start -0.12065 0.2794)
			(end -0.12065 0.3048)
			(stroke
				(width 0.1)
				(type default)
			)
			(layer "F.Fab")
		)
		(fp_line
			(start -0.12065 0.3048)
			(end -0.67945 0.3048)
			(stroke
				(width 0.1)
				(type default)
			)
			(layer "F.Fab")
		)
		(fp_line
			(start 0.120396 0.2794)
			(end -0.12065 0.2794)
			(stroke
				(width 0.1)
				(type default)
			)
			(layer "F.Fab")
		)
		(fp_line
			(start 0.120396 0.3048)
			(end 0.120396 0.2794)
			(stroke
				(width 0.1)
				(type default)
			)
			(layer "F.Fab")
		)
		(fp_line
			(start 0.12065 -0.3048)
			(end 0.67945 -0.3048)
			(stroke
				(width 0.1)
				(type default)
			)
			(layer "F.Fab")
		)
		(fp_line
			(start 0.12065 -0.2794)
			(end 0.12065 -0.3048)
			(stroke
				(width 0.1)
				(type default)
			)
			(layer "F.Fab")
		)
		(fp_line
			(start 0.67945 -0.3048)
			(end 0.67945 0.3048)
			(stroke
				(width 0.1)
				(type default)
			)
			(layer "F.Fab")
		)
		(fp_line
			(start 0.67945 0.3048)
			(end 0.120396 0.3048)
			(stroke
				(width 0.1)
				(type default)
			)
			(layer "F.Fab")
		)
		(pad "1" smd circle
			(at -0.40005 0)
			(size 0 0)
			(layers "F.Cu" "F.Mask" "F.Paste")
			(net "BIC_FWSPIDQ2")
		)
		(pad "2" smd circle
			(at 0.40005 0)
			(size 0 0)
			(layers "F.Cu" "F.Mask" "F.Paste")
			(net "P3V3_AUX")
		)
	)
	(footprint ""
		(layer "F.Cu")
		(at 149.871938 -24.807418)
		(property "Reference" "R426"
			(at 0 0 0)
			(layer "F.SilkS")
			(hide yes)
			(effects
				(font
					(size 1.27 1.27)
				)
			)
		)
		(property "Value" ""
			(at 0 0 0)
			(layer "F.Fab")
			(effects
				(font
					(size 1.27 1.27)
				)
			)
		)
		(duplicate_pad_numbers_are_jumpers no)
		(fp_line
			(start -0.7874 -0.4064)
			(end 0.7874 -0.4064)
			(stroke
				(width 0.1524)
				(type default)
			)
			(layer "F.SilkS")
		)
		(fp_line
			(start -0.7874 0.4064)
			(end -0.7874 -0.4064)
			(stroke
				(width 0.1524)
				(type default)
			)
			(layer "F.SilkS")
		)
		(fp_line
			(start 0.7874 -0.4064)
			(end 0.7874 0.4064)
			(stroke
				(width 0.1524)
				(type default)
			)
			(layer "F.SilkS")
		)
		(fp_line
			(start 0.7874 0.4064)
			(end -0.7874 0.4064)
			(stroke
				(width 0.1524)
				(type default)
			)
			(layer "F.SilkS")
		)
		(fp_line
			(start -0.67945 -0.305054)
			(end -0.12065 -0.305054)
			(stroke
				(width 0.1)
				(type default)
			)
			(layer "F.Fab")
		)
		(fp_line
			(start -0.67945 0.3048)
			(end -0.67945 -0.305054)
			(stroke
				(width 0.1)
				(type default)
			)
			(layer "F.Fab")
		)
		(fp_line
			(start -0.12065 -0.305054)
			(end -0.12065 -0.2794)
			(stroke
				(width 0.1)
				(type default)
			)
			(layer "F.Fab")
		)
		(fp_line
			(start -0.12065 -0.2794)
			(end 0.12065 -0.2794)
			(stroke
				(width 0.1)
				(type default)
			)
			(layer "F.Fab")
		)
		(fp_line
			(start -0.12065 0.2794)
			(end -0.12065 0.3048)
			(stroke
				(width 0.1)
				(type default)
			)
			(layer "F.Fab")
		)
		(fp_line
			(start -0.12065 0.3048)
			(end -0.67945 0.3048)
			(stroke
				(width 0.1)
				(type default)
			)
			(layer "F.Fab")
		)
		(fp_line
			(start 0.120396 0.2794)
			(end -0.12065 0.2794)
			(stroke
				(width 0.1)
				(type default)
			)
			(layer "F.Fab")
		)
		(fp_line
			(start 0.120396 0.3048)
			(end 0.120396 0.2794)
			(stroke
				(width 0.1)
				(type default)
			)
			(layer "F.Fab")
		)
		(fp_line
			(start 0.12065 -0.3048)
			(end 0.67945 -0.3048)
			(stroke
				(width 0.1)
				(type default)
			)
			(layer "F.Fab")
		)
		(fp_line
			(start 0.12065 -0.2794)
			(end 0.12065 -0.3048)
			(stroke
				(width 0.1)
				(type default)
			)
			(layer "F.Fab")
		)
		(fp_line
			(start 0.67945 -0.3048)
			(end 0.67945 0.3048)
			(stroke
				(width 0.1)
				(type default)
			)
			(layer "F.Fab")
		)
		(fp_line
			(start 0.67945 0.3048)
			(end 0.120396 0.3048)
			(stroke
				(width 0.1)
				(type default)
			)
			(layer "F.Fab")
		)
		(pad "1" smd circle
			(at -0.40005 0)
			(size 0 0)
			(layers "F.Cu" "F.Mask" "F.Paste")
			(net "P3V3_SSD5")
		)
		(pad "2" smd circle
			(at 0.40005 0)
			(size 0 0)
			(layers "F.Cu" "F.Mask" "F.Paste")
			(net "PU_CLKREQ5")
		)
	)
)
